(kicad_pcb
	(version 20260206)
	(generator "pcbnew")
	(generator_version "10.0")
	(general
		(thickness 1.6)
		(legacy_teardrops no)
	)
	(paper "A4")
	(title_block
		(title "12092022_DA0F0TYB4D0_F0T_Panel_BD_Front_D_brd_v02_OCP.brd")
		(comment 1 "Grand Teton / footprints 34-37 of 128")
	)
	(layers
		(0 "F.Cu" signal "TOP")
		(4 "In1.Cu" signal "GND")
		(6 "In2.Cu" signal "GND1")
		(2 "B.Cu" signal "BOTTOM")
		(9 "F.Adhes" user "F.Adhesive")
		(11 "B.Adhes" user "B.Adhesive")
		(13 "F.Paste" user "Package Geometry/Pastemask Top")
		(15 "B.Paste" user "Package Geometry/Pastemask Bottom")
		(5 "F.SilkS" user "Ref Des/Silkscreen Top")
		(7 "B.SilkS" user "Ref Des/Silkscreen Bottom")
		(1 "F.Mask" user "Board Geometry/Soldermask Top")
		(3 "B.Mask" user "Board Geometry/Soldermask Bottom")
		(17 "Dwgs.User" user "User.Drawings")
		(19 "Cmts.User" user "User.Comments")
		(21 "Eco1.User" user "User.Eco1")
		(23 "Eco2.User" user "User.Eco2")
		(25 "Edge.Cuts" user "Board Geometry/Outline")
		(27 "Margin" user)
		(31 "F.CrtYd" user "Package Geometry/Place Bound Top")
		(29 "B.CrtYd" user "Package Geometry/Place Bound Bottom")
		(35 "F.Fab" user "Ref Des/Assembly Top")
		(33 "B.Fab" user "Ref Des/Assembly Bottom")
	)
	(footprint ""
		(layer "F.Cu")
		(at 18.415 -55.753)
		(property "Reference" "R14"
			(at 3.81 0.02667 0)
			(unlocked yes)
			(layer "F.SilkS")
			(effects
				(font
					(size 0.7874 0.5842)
					(thickness 0.1524)
				)
			)
		)
		(property "Value" ""
			(at 0 0 0)
			(layer "F.Fab")
			(effects
				(font
					(size 1.27 1.27)
				)
			)
		)
		(duplicate_pad_numbers_are_jumpers no)
		(fp_line
			(start -0.7874 -0.4064)
			(end 0.7874 -0.4064)
			(stroke
				(width 0.1524)
				(type default)
			)
			(layer "F.SilkS")
		)
		(fp_line
			(start -0.7874 0.4064)
			(end -0.7874 -0.4064)
			(stroke
				(width 0.1524)
				(type default)
			)
			(layer "F.SilkS")
		)
		(fp_line
			(start 0.7874 -0.4064)
			(end 0.7874 0.4064)
			(stroke
				(width 0.1524)
				(type default)
			)
			(layer "F.SilkS")
		)
		(fp_line
			(start 0.7874 0.4064)
			(end -0.7874 0.4064)
			(stroke
				(width 0.1524)
				(type default)
			)
			(layer "F.SilkS")
		)
		(fp_line
			(start -0.67945 -0.305054)
			(end -0.12065 -0.305054)
			(stroke
				(width 0.1)
				(type default)
			)
			(layer "F.Fab")
		)
		(fp_line
			(start -0.67945 0.3048)
			(end -0.67945 -0.305054)
			(stroke
				(width 0.1)
				(type default)
			)
			(layer "F.Fab")
		)
		(fp_line
			(start -0.12065 -0.305054)
			(end -0.12065 -0.2794)
			(stroke
				(width 0.1)
				(type default)
			)
			(layer "F.Fab")
		)
		(fp_line
			(start -0.12065 -0.2794)
			(end 0.12065 -0.2794)
			(stroke
				(width 0.1)
				(type default)
			)
			(layer "F.Fab")
		)
		(fp_line
			(start -0.12065 0.2794)
			(end -0.12065 0.3048)
			(stroke
				(width 0.1)
				(type default)
			)
			(layer "F.Fab")
		)
		(fp_line
			(start -0.12065 0.3048)
			(end -0.67945 0.3048)
			(stroke
				(width 0.1)
				(type default)
			)
			(layer "F.Fab")
		)
		(fp_line
			(start 0.120396 0.2794)
			(end -0.12065 0.2794)
			(stroke
				(width 0.1)
				(type default)
			)
			(layer "F.Fab")
		)
		(fp_line
			(start 0.120396 0.3048)
			(end 0.120396 0.2794)
			(stroke
				(width 0.1)
				(type default)
			)
			(layer "F.Fab")
		)
		(fp_line
			(start 0.12065 -0.3048)
			(end 0.67945 -0.3048)
			(stroke
				(width 0.1)
				(type default)
			)
			(layer "F.Fab")
		)
		(fp_line
			(start 0.12065 -0.2794)
			(end 0.12065 -0.3048)
			(stroke
				(width 0.1)
				(type default)
			)
			(layer "F.Fab")
		)
		(fp_line
			(start 0.67945 -0.3048)
			(end 0.67945 0.3048)
			(stroke
				(width 0.1)
				(type default)
			)
			(layer "F.Fab")
		)
		(fp_line
			(start 0.67945 0.3048)
			(end 0.120396 0.3048)
			(stroke
				(width 0.1)
				(type default)
			)
			(layer "F.Fab")
		)
		(pad "1" smd circle
			(at -0.40005 0)
			(size 0 0)
			(layers "F.Cu" "F.Mask" "F.Paste")
			(net "SYSTEM_FAULT_ID_LED")
		)
		(pad "2" smd circle
			(at 0.40005 0)
			(size 0 0)
			(layers "F.Cu" "F.Mask" "F.Paste")
			(net "SYSTEM_FAULT_ID_LED_R1")
		)
	)
	(footprint ""
		(layer "F.Cu")
		(at 18.669 -66.294)
		(property "Reference" "C1"
			(at 0.635 1.42367 0)
			(unlocked yes)
			(layer "F.SilkS")
			(effects
				(font
					(size 0.7874 0.5842)
					(thickness 0.1524)
				)
			)
		)
		(property "Value" ""
			(at 0 0 0)
			(layer "F.Fab")
			(effects
				(font
					(size 1.27 1.27)
				)
			)
		)
		(duplicate_pad_numbers_are_jumpers no)
		(fp_line
			(start -1.2954 -0.5842)
			(end 1.2954 -0.5842)
			(stroke
				(width 0.1524)
				(type default)
			)
			(layer "F.SilkS")
		)
		(fp_line
			(start -1.2954 0.5842)
			(end -1.2954 -0.5842)
			(stroke
				(width 0.1524)
				(type default)
			)
			(layer "F.SilkS")
		)
		(fp_line
			(start 1.2954 -0.5842)
			(end 1.2954 0.5842)
			(stroke
				(width 0.1524)
				(type default)
			)
			(layer "F.SilkS")
		)
		(fp_line
			(start 1.2954 0.5842)
			(end -1.2954 0.5842)
			(stroke
				(width 0.1524)
				(type default)
			)
			(layer "F.SilkS")
		)
		(fp_line
			(start -1.1938 -0.4064)
			(end -0.8636 -0.4064)
			(stroke
				(width 0.1)
				(type default)
			)
			(layer "F.Fab")
		)
		(fp_line
			(start -1.1938 0.4064)
			(end -1.1938 -0.4064)
			(stroke
				(width 0.1)
				(type default)
			)
			(layer "F.Fab")
		)
		(fp_line
			(start -0.8636 -0.4572)
			(end 0.8636 -0.4572)
			(stroke
				(width 0.1)
				(type default)
			)
			(layer "F.Fab")
		)
		(fp_line
			(start -0.8636 -0.4064)
			(end -0.8636 -0.4572)
			(stroke
				(width 0.1)
				(type default)
			)
			(layer "F.Fab")
		)
		(fp_line
			(start -0.8636 0.4064)
			(end -1.1938 0.4064)
			(stroke
				(width 0.1)
				(type default)
			)
			(layer "F.Fab")
		)
		(fp_line
			(start -0.8636 0.4572)
			(end -0.8636 0.4064)
			(stroke
				(width 0.1)
				(type default)
			)
			(layer "F.Fab")
		)
		(fp_line
			(start 0.8636 -0.4572)
			(end 0.8636 -0.4064)
			(stroke
				(width 0.1)
				(type default)
			)
			(layer "F.Fab")
		)
		(fp_line
			(start 0.8636 -0.4064)
			(end 1.1938 -0.4064)
			(stroke
				(width 0.1)
				(type default)
			)
			(layer "F.Fab")
		)
		(fp_line
			(start 0.8636 0.4064)
			(end 0.8636 0.4572)
			(stroke
				(width 0.1)
				(type default)
			)
			(layer "F.Fab")
		)
		(fp_line
			(start 0.8636 0.4572)
			(end -0.8636 0.4572)
			(stroke
				(width 0.1)
				(type default)
			)
			(layer "F.Fab")
		)
		(fp_line
			(start 1.1938 -0.4064)
			(end 1.1938 0.4064)
			(stroke
				(width 0.1)
				(type default)
			)
			(layer "F.Fab")
		)
		(fp_line
			(start 1.1938 0.4064)
			(end 0.8636 0.4064)
			(stroke
				(width 0.1)
				(type default)
			)
			(layer "F.Fab")
		)
		(pad "1" smd rect
			(at -0.7366 0 270)
			(size 0.7112 0.8128)
			(layers "F.Cu" "F.Mask" "F.Paste")
			(net "P3V3_STBY")
		)
		(pad "2" smd rect
			(at 0.7366 0 270)
			(size 0.7112 0.8128)
			(layers "F.Cu" "F.Mask" "F.Paste")
			(net "GND")
		)
	)
	(footprint ""
		(layer "F.Cu")
		(at 15.875 -66.294 180)
		(property "Reference" "C3"
			(at 2.413 -0.02667 0)
			(unlocked yes)
			(layer "F.SilkS")
			(effects
				(font
					(size 0.7874 0.5842)
					(thickness 0.1524)
				)
			)
		)
		(property "Value" ""
			(at 0 0 180)
			(layer "F.Fab")
			(effects
				(font
					(size 1.27 1.27)
				)
			)
		)
		(duplicate_pad_numbers_are_jumpers no)
		(fp_line
			(start 1.2954 0.5842)
			(end -1.2954 0.5842)
			(stroke
				(width 0.1524)
				(type default)
			)
			(layer "F.SilkS")
		)
		(fp_line
			(start 1.2954 -0.5842)
			(end 1.2954 0.5842)
			(stroke
				(width 0.1524)
				(type default)
			)
			(layer "F.SilkS")
		)
		(fp_line
			(start -1.2954 0.5842)
			(end -1.2954 -0.5842)
			(stroke
				(width 0.1524)
				(type default)
			)
			(layer "F.SilkS")
		)
		(fp_line
			(start -1.2954 -0.5842)
			(end 1.2954 -0.5842)
			(stroke
				(width 0.1524)
				(type default)
			)
			(layer "F.SilkS")
		)
		(fp_line
			(start 1.1938 0.4064)
			(end 0.8636 0.4064)
			(stroke
				(width 0.1)
				(type default)
			)
			(layer "F.Fab")
		)
		(fp_line
			(start 1.1938 -0.4064)
			(end 1.1938 0.4064)
			(stroke
				(width 0.1)
				(type default)
			)
			(layer "F.Fab")
		)
		(fp_line
			(start 0.8636 0.4572)
			(end -0.8636 0.4572)
			(stroke
				(width 0.1)
				(type default)
			)
			(layer "F.Fab")
		)
		(fp_line
			(start 0.8636 0.4064)
			(end 0.8636 0.4572)
			(stroke
				(width 0.1)
				(type default)
			)
			(layer "F.Fab")
		)
		(fp_line
			(start 0.8636 -0.4064)
			(end 1.1938 -0.4064)
			(stroke
				(width 0.1)
				(type default)
			)
			(layer "F.Fab")
		)
		(fp_line
			(start 0.8636 -0.4572)
			(end 0.8636 -0.4064)
			(stroke
				(width 0.1)
				(type default)
			)
			(layer "F.Fab")
		)
		(fp_line
			(start -0.8636 0.4572)
			(end -0.8636 0.4064)
			(stroke
				(width 0.1)
				(type default)
			)
			(layer "F.Fab")
		)
		(fp_line
			(start -0.8636 0.4064)
			(end -1.1938 0.4064)
			(stroke
				(width 0.1)
				(type default)
			)
			(layer "F.Fab")
		)
		(fp_line
			(start -0.8636 -0.4064)
			(end -0.8636 -0.4572)
			(stroke
				(width 0.1)
				(type default)
			)
			(layer "F.Fab")
		)
		(fp_line
			(start -0.8636 -0.4572)
			(end 0.8636 -0.4572)
			(stroke
				(width 0.1)
				(type default)
			)
			(layer "F.Fab")
		)
		(fp_line
			(start -1.1938 0.4064)
			(end -1.1938 -0.4064)
			(stroke
				(width 0.1)
				(type default)
			)
			(layer "F.Fab")
		)
		(fp_line
			(start -1.1938 -0.4064)
			(end -0.8636 -0.4064)
			(stroke
				(width 0.1)
				(type default)
			)
			(layer "F.Fab")
		)
		(pad "1" smd rect
			(at -0.7366 0 90)
			(size 0.7112 0.8128)
			(layers "F.Cu" "F.Mask" "F.Paste")
			(net "P5V_STBY")
		)
		(pad "2" smd rect
			(at 0.7366 0 90)
			(size 0.7112 0.8128)
			(layers "F.Cu" "F.Mask" "F.Paste")
			(net "GND")
		)
	)
	(footprint ""
		(layer "F.Cu")
		(at 32.800036 -62.875922 180)
		(property "Reference" "H10"
			(at -3.267964 7.709408 0)
			(unlocked yes)
			(layer "F.SilkS")
			(effects
				(font
					(size 0.7874 0.5842)
					(thickness 0.1524)
				)
				(justify left)
			)
		)
		(property "Value" ""
			(at 0 0 180)
			(layer "F.Fab")
			(effects
				(font
					(size 1.27 1.27)
				)
			)
		)
		(duplicate_pad_numbers_are_jumpers no)
		(fp_arc
			(start 7.662418 -2.299462)
			(mid 1.162068 7.915133)
			(end -7.999984 0)
			(stroke
				(width 0.1524)
				(type default)
			)
			(layer "F.SilkS")
		)
		(fp_arc
			(start -7.999984 0)
			(mid -7.435749 -2.951077)
			(end -5.822696 -5.485892)
			(stroke
				(width 0.1524)
				(type default)
			)
			(layer "F.SilkS")
		)
		(fp_arc
			(start 6.784086 4.239768)
			(mid 5.411387 5.892142)
			(end 3.648456 7.11962)
			(stroke
				(width 0.1524)
				(type default)
			)
			(layer "B.SilkS")
		)
		(fp_arc
			(start -0.09271 -7.999476)
			(mid 2.72788 -7.520639)
			(end 5.199634 -6.079998)
			(stroke
				(width 0.1524)
				(type default)
			)
			(layer "B.SilkS")
		)
		(fp_arc
			(start -3.65887 7.114286)
			(mid -7.943333 0.95039)
			(end -5.233924 -6.05028)
			(stroke
				(width 0.1524)
				(type default)
			)
			(layer "B.SilkS")
		)
		(fp_arc
			(start -4.141978 -6.844284)
			(mid -2.811186 -7.489822)
			(end -1.3843 -7.879334)
			(stroke
				(width 0.1524)
				(type default)
			)
			(layer "B.SilkS")
		)
		(fp_circle
			(center 0 0)
			(end -7.999984 0)
			(stroke
				(width 0.1)
				(type default)
			)
			(fill no)
			(layer "B.Fab")
		)
		(fp_circle
			(center 0 0)
			(end -7.999984 0)
			(stroke
				(width 0.1)
				(type default)
			)
			(fill no)
			(layer "F.Fab")
		)
		(pad "" np_thru_hole circle
			(at 0 0 180)
			(size 4.0132 4.0132)
			(drill 4.0132)
			(layers "*.Cu" "*.Mask")
			(clearance 0.381)
			(thermal_gap 0.381)
		)
		(pad "2" thru_hole circle
			(at 3.758692 0 180)
			(size 0.762 0.762)
			(drill 0.5588)
			(layers "*.Cu" "*.Mask")
			(remove_unused_layers no)
			(net "GND")
			(clearance 0.1524)
			(thermal_gap 0.1524)
		)
		(pad "3" thru_hole circle
			(at 2.657602 -2.657602 180)
			(size 0.762 0.762)
			(drill 0.5588)
			(layers "*.Cu" "*.Mask")
			(remove_unused_layers no)
			(net "GND")
			(clearance 0.1524)
			(thermal_gap 0.1524)
		)
		(pad "4" thru_hole circle
			(at 0 -3.758692 180)
			(size 0.762 0.762)
			(drill 0.5588)
			(layers "*.Cu" "*.Mask")
			(remove_unused_layers no)
			(net "GND")
			(clearance 0.1524)
			(thermal_gap 0.1524)
		)
		(pad "5" thru_hole circle
			(at -2.657602 -2.657602 180)
			(size 0.762 0.762)
			(drill 0.5588)
			(layers "*.Cu" "*.Mask")
			(remove_unused_layers no)
			(net "GND")
			(clearance 0.1524)
			(thermal_gap 0.1524)
		)
		(pad "6" thru_hole circle
			(at -3.758692 0 180)
			(size 0.762 0.762)
			(drill 0.5588)
			(layers "*.Cu" "*.Mask")
			(remove_unused_layers no)
			(net "GND")
			(clearance 0.1524)
			(thermal_gap 0.1524)
		)
		(pad "7" thru_hole circle
			(at -2.657602 2.657602 180)
			(size 0.762 0.762)
			(drill 0.5588)
			(layers "*.Cu" "*.Mask")
			(remove_unused_layers no)
			(net "GND")
			(clearance 0.1524)
			(thermal_gap 0.1524)
		)
		(pad "8" thru_hole circle
			(at 0 3.758692 180)
			(size 0.762 0.762)
			(drill 0.5588)
			(layers "*.Cu" "*.Mask")
			(remove_unused_layers no)
			(net "GND")
			(clearance 0.1524)
			(thermal_gap 0.1524)
		)
		(pad "9" thru_hole circle
			(at 2.657602 2.657602 180)
			(size 0.762 0.762)
			(drill 0.5588)
			(layers "*.Cu" "*.Mask")
			(remove_unused_layers no)
			(net "GND")
			(clearance 0.1524)
			(thermal_gap 0.1524)
		)
		(zone
			(layer "F.Cu")
			(hatch none 0.5)
			(connect_pads
				(clearance 0)
			)
			(min_thickness 0.25)
			(keepout
				(tracks not_allowed)
				(vias allowed)
				(pads allowed)
				(copperpour not_allowed)
				(footprints allowed)
			)
			(placement
				(enabled no)
				(sheetname "")
			)
			(fill
				(thermal_gap 0.5)
				(thermal_bridge_width 0.5)
				(island_removal_mode 0)
			)
			(polygon
				(pts
					(arc
						(start 32.800036 -57.621932)
						(mid 27.546046 -62.875922)
						(end 32.800036 -68.129912)
					)
					(arc
						(start 32.800036 -67.901312)
						(mid 27.774646 -62.875922)
						(end 32.800036 -57.850532)
					)
				)
			)
		)
		(zone
			(layer "F.Cu")
			(hatch none 0.5)
			(connect_pads
				(clearance 0)
			)
			(min_thickness 0.25)
			(keepout
				(tracks not_allowed)
				(vias allowed)
				(pads allowed)
				(copperpour not_allowed)
				(footprints allowed)
			)
			(placement
				(enabled no)
				(sheetname "")
			)
			(fill
				(thermal_gap 0.5)
				(thermal_bridge_width 0.5)
				(island_removal_mode 0)
			)
			(polygon
				(pts
					(arc
						(start 32.800036 -57.621932)
						(mid 38.054026 -62.875922)
						(end 32.800036 -68.129912)
					)
					(arc
						(start 32.800036 -67.901312)
						(mid 37.825426 -62.875922)
						(end 32.800036 -57.850532)
					)
				)
			)
		)
		(zone
			(layer "F.Cu")
			(hatch none 0.5)
			(connect_pads
				(clearance 0)
			)
			(min_thickness 0.25)
			(keepout
				(tracks not_allowed)
				(vias allowed)
				(pads allowed)
				(copperpour not_allowed)
				(footprints allowed)
			)
			(placement
				(enabled no)
				(sheetname "")
			)
			(fill
				(thermal_gap 0.5)
				(thermal_bridge_width 0.5)
				(island_removal_mode 0)
			)
			(polygon
				(pts
					(arc
						(start 32.800036 -70.875906)
						(mid 24.800052 -62.875922)
						(end 32.800036 -54.875938)
					)
					(arc
						(start 32.800036 -57.621932)
						(mid 27.464766 -62.957202)
						(end 32.800036 -68.292218)
					)
				)
			)
		)
		(zone
			(layer "F.Cu")
			(hatch none 0.5)
			(connect_pads
				(clearance 0)
			)
			(min_thickness 0.25)
			(keepout
				(tracks not_allowed)
				(vias allowed)
				(pads allowed)
				(copperpour not_allowed)
				(footprints allowed)
			)
			(placement
				(enabled no)
				(sheetname "")
			)
			(fill
				(thermal_gap 0.5)
				(thermal_bridge_width 0.5)
				(island_removal_mode 0)
			)
			(polygon
				(pts
					(arc
						(start 32.800036 -70.875906)
						(mid 40.80002 -62.875922)
						(end 32.800036 -54.875938)
					)
					(arc
						(start 32.800036 -57.621932)
						(mid 38.135306 -62.957202)
						(end 32.800036 -68.292218)
					)
				)
			)
		)
		(zone
			(layers "F.Cu" "B.Cu" "In1.Cu" "In2.Cu")
			(hatch none 0.5)
			(connect_pads
				(clearance 0)
			)
			(min_thickness 0.25)
			(keepout
				(tracks not_allowed)
				(vias allowed)
				(pads allowed)
				(copperpour not_allowed)
				(footprints allowed)
			)
			(placement
				(enabled no)
				(sheetname "")
			)
			(fill
				(thermal_gap 0.5)
				(thermal_bridge_width 0.5)
				(island_removal_mode 0)
			)
			(polygon
				(pts
					(arc
						(start 35.314636 -62.875922)
						(mid 30.285436 -62.875922)
						(end 35.314636 -62.875922)
					)
				)
			)
		)
		(zone
			(layer "B.Cu")
			(hatch none 0.5)
			(connect_pads
				(clearance 0)
			)
			(min_thickness 0.25)
			(keepout
				(tracks not_allowed)
				(vias allowed)
				(pads allowed)
				(copperpour not_allowed)
				(footprints allowed)
			)
			(placement
				(enabled no)
				(sheetname "")
			)
			(fill
				(thermal_gap 0.5)
				(thermal_bridge_width 0.5)
				(island_removal_mode 0)
			)
			(polygon
				(pts
					(arc
						(start 27.292046 -66.376042)
						(mid 28.905299 -70.270779)
						(end 32.800036 -71.884032)
					)
					(arc
						(start 32.800036 -71.401432)
						(mid 29.246549 -69.929529)
						(end 27.774646 -66.376042)
					)
					(arc
						(start 27.774646 -62.875922)
						(mid 29.246549 -59.322435)
						(end 32.800036 -57.850532)
					)
					(arc
						(start 32.800036 -57.367932)
						(mid 28.905299 -58.981185)
						(end 27.292046 -62.875922)
					)
				)
			)
		)
		(zone
			(layer "B.Cu")
			(hatch none 0.5)
			(connect_pads
				(clearance 0)
			)
			(min_thickness 0.25)
			(keepout
				(tracks not_allowed)
				(vias allowed)
				(pads allowed)
				(copperpour not_allowed)
				(footprints allowed)
			)
			(placement
				(enabled no)
				(sheetname "")
			)
			(fill
				(thermal_gap 0.5)
				(thermal_bridge_width 0.5)
				(island_removal_mode 0)
			)
			(polygon
				(pts
					(arc
						(start 38.308026 -66.376042)
						(mid 36.694773 -70.270779)
						(end 32.800036 -71.884032)
					)
					(arc
						(start 32.800036 -71.401432)
						(mid 36.353523 -69.929529)
						(end 37.825426 -66.376042)
					)
					(arc
						(start 37.825426 -62.875922)
						(mid 36.353523 -59.322435)
						(end 32.800036 -57.850532)
					)
					(arc
						(start 32.800036 -57.367932)
						(mid 36.694773 -58.981185)
						(end 38.308026 -62.875922)
					)
				)
			)
		)
	)
)
